# SCM (Grand Teton) — schematic netlist excerpt (pin names and nets, part order shuffled) for the footprints in the layout excerpt that follows; sources: Cadence DE-HDL packaged netlist, KiCad conversion of 12092022_DA0F0TMDCD0_F0T_Management_Board_D_brd_V3_OCP.brd

R639  Q_RES  33.2 1% CHIP  pkg 0402LF  page 32 : A = JTAG_1_BMC_TDI_R ; B = JTAG_MB_TDI
R799  Q_RES  33.2 1% CHIP  pkg 0402LF  page 13 : A = SPI_BMC_BIOS_CS0_N ; B = SPI_BMC_BIOS_CS0_R1_N

(kicad_pcb
	(version 20260206)
	(generator "pcbnew")
	(generator_version "10.0")
	(general
		(thickness 1.6)
		(legacy_teardrops no)
	)
	(paper "A4")
	(title_block
		(title "12092022_DA0F0TMDCD0_F0T_Management_Board_D_brd_V3_OCP.brd")
		(comment 1 "Grand Teton / footprints 679-680 of 1440")
	)
	(layers
		(0 "F.Cu" signal "TOP")
		(4 "In1.Cu" signal "GND")
		(6 "In2.Cu" signal "IN1")
		(8 "In3.Cu" signal "GND1")
		(10 "In4.Cu" signal "IN2")
		(12 "In5.Cu" signal "VCC")
		(14 "In6.Cu" signal "VCC1")
		(16 "In7.Cu" signal "IN3")
		(18 "In8.Cu" signal "GND2")
		(20 "In9.Cu" signal "IN4")
		(22 "In10.Cu" signal "GND3")
		(2 "B.Cu" signal "BOTTOM")
		(9 "F.Adhes" user "F.Adhesive")
		(11 "B.Adhes" user "B.Adhesive")
		(13 "F.Paste" user "Package Geometry/Pastemask Top")
		(15 "B.Paste" user "Package Geometry/Pastemask Bottom")
		(5 "F.SilkS" user "Ref Des/Silkscreen Top")
		(7 "B.SilkS" user "Ref Des/Silkscreen Bottom")
		(1 "F.Mask" user "Board Geometry/Soldermask Top")
		(3 "B.Mask" user "Board Geometry/Soldermask Bottom")
		(17 "Dwgs.User" user "User.Drawings")
		(19 "Cmts.User" user "User.Comments")
		(21 "Eco1.User" user "User.Eco1")
		(23 "Eco2.User" user "User.Eco2")
		(25 "Edge.Cuts" user "Board Geometry/Outline")
		(27 "Margin" user)
		(31 "F.CrtYd" user "Package Geometry/Place Bound Top")
		(29 "B.CrtYd" user "Package Geometry/Place Bound Bottom")
		(35 "F.Fab" user "Ref Des/Assembly Top")
		(33 "B.Fab" user "Ref Des/Assembly Bottom")
	)
	(footprint ""
		(layer "F.Cu")
		(at 52.991258 -34.637726 -90)
		(property "Reference" "R639"
			(at 0 0 270)
			(layer "F.SilkS")
			(hide yes)
			(effects
				(font
					(size 1.27 1.27)
				)
			)
		)
		(property "Value" ""
			(at 0 0 270)
			(layer "F.Fab")
			(effects
				(font
					(size 1.27 1.27)
				)
			)
		)
		(duplicate_pad_numbers_are_jumpers no)
		(fp_line
			(start -0.7874 0.4064)
			(end -0.7874 -0.4064)
			(stroke
				(width 0.1524)
				(type default)
			)
			(layer "F.SilkS")
		)
		(fp_line
			(start 0.7874 0.4064)
			(end -0.7874 0.4064)
			(stroke
				(width 0.1524)
				(type default)
			)
			(layer "F.SilkS")
		)
		(fp_line
			(start -0.7874 -0.4064)
			(end 0.7874 -0.4064)
			(stroke
				(width 0.1524)
				(type default)
			)
			(layer "F.SilkS")
		)
		(fp_line
			(start 0.7874 -0.4064)
			(end 0.7874 0.4064)
			(stroke
				(width 0.1524)
				(type default)
			)
			(layer "F.SilkS")
		)
		(fp_line
			(start -0.67945 0.3048)
			(end -0.67945 -0.305054)
			(stroke
				(width 0.1)
				(type default)
			)
			(layer "F.Fab")
		)
		(fp_line
			(start -0.12065 0.3048)
			(end -0.67945 0.3048)
			(stroke
				(width 0.1)
				(type default)
			)
			(layer "F.Fab")
		)
		(fp_line
			(start 0.120396 0.3048)
			(end 0.120396 0.2794)
			(stroke
				(width 0.1)
				(type default)
			)
			(layer "F.Fab")
		)
		(fp_line
			(start 0.67945 0.3048)
			(end 0.120396 0.3048)
			(stroke
				(width 0.1)
				(type default)
			)
			(layer "F.Fab")
		)
		(fp_line
			(start -0.12065 0.2794)
			(end -0.12065 0.3048)
			(stroke
				(width 0.1)
				(type default)
			)
			(layer "F.Fab")
		)
		(fp_line
			(start 0.120396 0.2794)
			(end -0.12065 0.2794)
			(stroke
				(width 0.1)
				(type default)
			)
			(layer "F.Fab")
		)
		(fp_line
			(start -0.12065 -0.2794)
			(end 0.12065 -0.2794)
			(stroke
				(width 0.1)
				(type default)
			)
			(layer "F.Fab")
		)
		(fp_line
			(start 0.12065 -0.2794)
			(end 0.12065 -0.3048)
			(stroke
				(width 0.1)
				(type default)
			)
			(layer "F.Fab")
		)
		(fp_line
			(start 0.12065 -0.3048)
			(end 0.67945 -0.3048)
			(stroke
				(width 0.1)
				(type default)
			)
			(layer "F.Fab")
		)
		(fp_line
			(start 0.67945 -0.3048)
			(end 0.67945 0.3048)
			(stroke
				(width 0.1)
				(type default)
			)
			(layer "F.Fab")
		)
		(fp_line
			(start -0.67945 -0.305054)
			(end -0.12065 -0.305054)
			(stroke
				(width 0.1)
				(type default)
			)
			(layer "F.Fab")
		)
		(fp_line
			(start -0.12065 -0.305054)
			(end -0.12065 -0.2794)
			(stroke
				(width 0.1)
				(type default)
			)
			(layer "F.Fab")
		)
		(pad "1" smd circle
			(at -0.40005 0 270)
			(size 0 0)
			(layers "F.Cu" "F.Mask" "F.Paste")
			(net "JTAG_1_BMC_TDI_R")
		)
		(pad "2" smd circle
			(at 0.40005 0 270)
			(size 0 0)
			(layers "F.Cu" "F.Mask" "F.Paste")
			(net "JTAG_MB_TDI")
		)
	)
	(footprint ""
		(layer "F.Cu")
		(at 61.70676 -66.031364 -90)
		(property "Reference" "R799"
			(at 0 0 270)
			(layer "F.SilkS")
			(hide yes)
			(effects
				(font
					(size 1.27 1.27)
				)
			)
		)
		(property "Value" ""
			(at 0 0 270)
			(layer "F.Fab")
			(effects
				(font
					(size 1.27 1.27)
				)
			)
		)
		(duplicate_pad_numbers_are_jumpers no)
		(fp_line
			(start -0.7874 0.4064)
			(end -0.7874 -0.4064)
			(stroke
				(width 0.1524)
				(type default)
			)
			(layer "F.SilkS")
		)
		(fp_line
			(start 0.7874 0.4064)
			(end -0.7874 0.4064)
			(stroke
				(width 0.1524)
				(type default)
			)
			(layer "F.SilkS")
		)
		(fp_line
			(start -0.7874 -0.4064)
			(end 0.7874 -0.4064)
			(stroke
				(width 0.1524)
				(type default)
			)
			(layer "F.SilkS")
		)
		(fp_line
			(start 0.7874 -0.4064)
			(end 0.7874 0.4064)
			(stroke
				(width 0.1524)
				(type default)
			)
			(layer "F.SilkS")
		)
		(fp_line
			(start -0.67945 0.3048)
			(end -0.67945 -0.305054)
			(stroke
				(width 0.1)
				(type default)
			)
			(layer "F.Fab")
		)
		(fp_line
			(start -0.12065 0.3048)
			(end -0.67945 0.3048)
			(stroke
				(width 0.1)
				(type default)
			)
			(layer "F.Fab")
		)
		(fp_line
			(start 0.120396 0.3048)
			(end 0.120396 0.2794)
			(stroke
				(width 0.1)
				(type default)
			)
			(layer "F.Fab")
		)
		(fp_line
			(start 0.67945 0.3048)
			(end 0.120396 0.3048)
			(stroke
				(width 0.1)
				(type default)
			)
			(layer "F.Fab")
		)
		(fp_line
			(start -0.12065 0.2794)
			(end -0.12065 0.3048)
			(stroke
				(width 0.1)
				(type default)
			)
			(layer "F.Fab")
		)
		(fp_line
			(start 0.120396 0.2794)
			(end -0.12065 0.2794)
			(stroke
				(width 0.1)
				(type default)
			)
			(layer "F.Fab")
		)
		(fp_line
			(start -0.12065 -0.2794)
			(end 0.12065 -0.2794)
			(stroke
				(width 0.1)
				(type default)
			)
			(layer "F.Fab")
		)
		(fp_line
			(start 0.12065 -0.2794)
			(end 0.12065 -0.3048)
			(stroke
				(width 0.1)
				(type default)
			)
			(layer "F.Fab")
		)
		(fp_line
			(start 0.12065 -0.3048)
			(end 0.67945 -0.3048)
			(stroke
				(width 0.1)
				(type default)
			)
			(layer "F.Fab")
		)
		(fp_line
			(start 0.67945 -0.3048)
			(end 0.67945 0.3048)
			(stroke
				(width 0.1)
				(type default)
			)
			(layer "F.Fab")
		)
		(fp_line
			(start -0.67945 -0.305054)
			(end -0.12065 -0.305054)
			(stroke
				(width 0.1)
				(type default)
			)
			(layer "F.Fab")
		)
		(fp_line
			(start -0.12065 -0.305054)
			(end -0.12065 -0.2794)
			(stroke
				(width 0.1)
				(type default)
			)
			(layer "F.Fab")
		)
		(pad "1" smd circle
			(at -0.40005 0 270)
			(size 0 0)
			(layers "F.Cu" "F.Mask" "F.Paste")
			(net "SPI_BMC_BIOS_CS0_N")
		)
		(pad "2" smd circle
			(at 0.40005 0 270)
			(size 0 0)
			(layers "F.Cu" "F.Mask" "F.Paste")
			(net "SPI_BMC_BIOS_CS0_R1_N")
		)
	)
)
